# T6G (Grand Teton) — schematic netlist excerpt (pin names and nets, part order shuffled) for the footprints in the layout excerpt that follows; sources: Cadence DE-HDL packaged netlist, KiCad conversion of 04192023_DAF0TMB3IC0_F0TG_MB_C_brd_V02_OCP.brd

PC2235  Q_CAP  100NF 50V 10% X7R  pkg C0402  page 152 : A = P12V_SCM_IMON ; B = GND
R4140  Q_RES  100K 1% CHIP  pkg 0402LF  page 125 : A = P3V3_AUX ; B = GPU_3V3IO_RSVD3_FFU_ISO

(kicad_pcb
	(version 20260206)
	(generator "pcbnew")
	(generator_version "10.0")
	(general
		(thickness 1.6)
		(legacy_teardrops no)
	)
	(paper "A4")
	(title_block
		(title "04192023_DAF0TMB3IC0_F0TG_MB_C_brd_V02_OCP.brd")
		(comment 1 "Grand Teton / footprints 4269-4270 of 8354")
	)
	(layers
		(0 "F.Cu" signal "TOP")
		(4 "In1.Cu" signal "GND")
		(6 "In2.Cu" signal "IN1")
		(8 "In3.Cu" signal "GND1")
		(10 "In4.Cu" signal "IN2")
		(12 "In5.Cu" signal "GND2")
		(14 "In6.Cu" signal "IN3")
		(16 "In7.Cu" signal "GND3")
		(18 "In8.Cu" signal "VCC")
		(20 "In9.Cu" signal "VCC1")
		(22 "In10.Cu" signal "GND4")
		(24 "In11.Cu" signal "IN4")
		(26 "In12.Cu" signal "GND5")
		(28 "In13.Cu" signal "IN5")
		(30 "In14.Cu" signal "GND6")
		(32 "In15.Cu" signal "IN6")
		(34 "In16.Cu" signal "GND7")
		(2 "B.Cu" signal "BOTTOM")
		(9 "F.Adhes" user "F.Adhesive")
		(11 "B.Adhes" user "B.Adhesive")
		(13 "F.Paste" user "Package Geometry/Pastemask Top")
		(15 "B.Paste" user "Package Geometry/Pastemask Bottom")
		(5 "F.SilkS" user "Ref Des/Silkscreen Top")
		(7 "B.SilkS" user "Ref Des/Silkscreen Bottom")
		(1 "F.Mask" user "Board Geometry/Soldermask Top")
		(3 "B.Mask" user "Board Geometry/Soldermask Bottom")
		(17 "Dwgs.User" user "User.Drawings")
		(19 "Cmts.User" user "User.Comments")
		(21 "Eco1.User" user "User.Eco1")
		(23 "Eco2.User" user "User.Eco2")
		(25 "Edge.Cuts" user "Board Geometry/Outline")
		(27 "Margin" user)
		(31 "F.CrtYd" user "Package Geometry/Place Bound Top")
		(29 "B.CrtYd" user "Package Geometry/Place Bound Bottom")
		(35 "F.Fab" user "Ref Des/Assembly Top")
		(33 "B.Fab" user "Ref Des/Assembly Bottom")
	)
	(footprint ""
		(layer "F.Cu")
		(at 174.613062 -32.935672 90)
		(property "Reference" "PC2235"
			(at 0 0 90)
			(layer "F.SilkS")
			(hide yes)
			(effects
				(font
					(size 1.27 1.27)
				)
			)
		)
		(property "Value" ""
			(at 0 0 90)
			(layer "F.Fab")
			(effects
				(font
					(size 1.27 1.27)
				)
			)
		)
		(duplicate_pad_numbers_are_jumpers no)
		(fp_line
			(start 0.7874 -0.4064)
			(end 0.7874 0.4064)
			(stroke
				(width 0.1524)
				(type default)
			)
			(layer "F.SilkS")
		)
		(fp_line
			(start -0.7874 -0.4064)
			(end 0.7874 -0.4064)
			(stroke
				(width 0.1524)
				(type default)
			)
			(layer "F.SilkS")
		)
		(fp_line
			(start 0.7874 0.4064)
			(end -0.7874 0.4064)
			(stroke
				(width 0.1524)
				(type default)
			)
			(layer "F.SilkS")
		)
		(fp_line
			(start -0.7874 0.4064)
			(end -0.7874 -0.4064)
			(stroke
				(width 0.1524)
				(type default)
			)
			(layer "F.SilkS")
		)
		(fp_line
			(start -0.12065 -0.305054)
			(end -0.12065 -0.2794)
			(stroke
				(width 0.1)
				(type default)
			)
			(layer "F.Fab")
		)
		(fp_line
			(start -0.67945 -0.305054)
			(end -0.12065 -0.305054)
			(stroke
				(width 0.1)
				(type default)
			)
			(layer "F.Fab")
		)
		(fp_line
			(start 0.67945 -0.3048)
			(end 0.67945 0.3048)
			(stroke
				(width 0.1)
				(type default)
			)
			(layer "F.Fab")
		)
		(fp_line
			(start 0.12065 -0.3048)
			(end 0.67945 -0.3048)
			(stroke
				(width 0.1)
				(type default)
			)
			(layer "F.Fab")
		)
		(fp_line
			(start 0.12065 -0.2794)
			(end 0.12065 -0.3048)
			(stroke
				(width 0.1)
				(type default)
			)
			(layer "F.Fab")
		)
		(fp_line
			(start -0.12065 -0.2794)
			(end 0.12065 -0.2794)
			(stroke
				(width 0.1)
				(type default)
			)
			(layer "F.Fab")
		)
		(fp_line
			(start 0.120396 0.2794)
			(end -0.12065 0.2794)
			(stroke
				(width 0.1)
				(type default)
			)
			(layer "F.Fab")
		)
		(fp_line
			(start -0.12065 0.2794)
			(end -0.12065 0.3048)
			(stroke
				(width 0.1)
				(type default)
			)
			(layer "F.Fab")
		)
		(fp_line
			(start 0.67945 0.3048)
			(end 0.120396 0.3048)
			(stroke
				(width 0.1)
				(type default)
			)
			(layer "F.Fab")
		)
		(fp_line
			(start 0.120396 0.3048)
			(end 0.120396 0.2794)
			(stroke
				(width 0.1)
				(type default)
			)
			(layer "F.Fab")
		)
		(fp_line
			(start -0.12065 0.3048)
			(end -0.67945 0.3048)
			(stroke
				(width 0.1)
				(type default)
			)
			(layer "F.Fab")
		)
		(fp_line
			(start -0.67945 0.3048)
			(end -0.67945 -0.305054)
			(stroke
				(width 0.1)
				(type default)
			)
			(layer "F.Fab")
		)
		(pad "1" smd circle
			(at -0.40005 0 90)
			(size 0 0)
			(layers "F.Cu" "F.Mask" "F.Paste")
			(net "P12V_SCM_IMON")
		)
		(pad "2" smd circle
			(at 0.40005 0 90)
			(size 0 0)
			(layers "F.Cu" "F.Mask" "F.Paste")
			(net "GND")
		)
	)
	(footprint ""
		(layer "F.Cu")
		(at 302.523398 -431.2539)
		(property "Reference" "R4140"
			(at 0 0 0)
			(layer "F.SilkS")
			(hide yes)
			(effects
				(font
					(size 1.27 1.27)
				)
			)
		)
		(property "Value" ""
			(at 0 0 0)
			(layer "F.Fab")
			(effects
				(font
					(size 1.27 1.27)
				)
			)
		)
		(duplicate_pad_numbers_are_jumpers no)
		(fp_line
			(start -0.7874 -0.4064)
			(end 0.7874 -0.4064)
			(stroke
				(width 0.1524)
				(type default)
			)
			(layer "F.SilkS")
		)
		(fp_line
			(start -0.7874 0.4064)
			(end -0.7874 -0.4064)
			(stroke
				(width 0.1524)
				(type default)
			)
			(layer "F.SilkS")
		)
		(fp_line
			(start 0.7874 -0.4064)
			(end 0.7874 0.4064)
			(stroke
				(width 0.1524)
				(type default)
			)
			(layer "F.SilkS")
		)
		(fp_line
			(start 0.7874 0.4064)
			(end -0.7874 0.4064)
			(stroke
				(width 0.1524)
				(type default)
			)
			(layer "F.SilkS")
		)
		(fp_line
			(start -0.67945 -0.305054)
			(end -0.12065 -0.305054)
			(stroke
				(width 0.1)
				(type default)
			)
			(layer "F.Fab")
		)
		(fp_line
			(start -0.67945 0.3048)
			(end -0.67945 -0.305054)
			(stroke
				(width 0.1)
				(type default)
			)
			(layer "F.Fab")
		)
		(fp_line
			(start -0.12065 -0.305054)
			(end -0.12065 -0.2794)
			(stroke
				(width 0.1)
				(type default)
			)
			(layer "F.Fab")
		)
		(fp_line
			(start -0.12065 -0.2794)
			(end 0.12065 -0.2794)
			(stroke
				(width 0.1)
				(type default)
			)
			(layer "F.Fab")
		)
		(fp_line
			(start -0.12065 0.2794)
			(end -0.12065 0.3048)
			(stroke
				(width 0.1)
				(type default)
			)
			(layer "F.Fab")
		)
		(fp_line
			(start -0.12065 0.3048)
			(end -0.67945 0.3048)
			(stroke
				(width 0.1)
				(type default)
			)
			(layer "F.Fab")
		)
		(fp_line
			(start 0.120396 0.2794)
			(end -0.12065 0.2794)
			(stroke
				(width 0.1)
				(type default)
			)
			(layer "F.Fab")
		)
		(fp_line
			(start 0.120396 0.3048)
			(end 0.120396 0.2794)
			(stroke
				(width 0.1)
				(type default)
			)
			(layer "F.Fab")
		)
		(fp_line
			(start 0.12065 -0.3048)
			(end 0.67945 -0.3048)
			(stroke
				(width 0.1)
				(type default)
			)
			(layer "F.Fab")
		)
		(fp_line
			(start 0.12065 -0.2794)
			(end 0.12065 -0.3048)
			(stroke
				(width 0.1)
				(type default)
			)
			(layer "F.Fab")
		)
		(fp_line
			(start 0.67945 -0.3048)
			(end 0.67945 0.3048)
			(stroke
				(width 0.1)
				(type default)
			)
			(layer "F.Fab")
		)
		(fp_line
			(start 0.67945 0.3048)
			(end 0.120396 0.3048)
			(stroke
				(width 0.1)
				(type default)
			)
			(layer "F.Fab")
		)
		(pad "1" smd circle
			(at -0.40005 0)
			(size 0 0)
			(layers "F.Cu" "F.Mask" "F.Paste")
			(net "P3V3_AUX")
		)
		(pad "2" smd circle
			(at 0.40005 0)
			(size 0 0)
			(layers "F.Cu" "F.Mask" "F.Paste")
			(net "GPU_3V3IO_RSVD3_FFU_ISO")
		)
	)
)
